(kicad_pcb
	(version 20260206)
	(generator "pcbnew")
	(generator_version "10.0")
	(general
		(thickness 1.6)
		(legacy_teardrops no)
	)
	(paper "A4")
	(title_block
		(title "01162023_DA0F0TEBIF0_F0T_Expander_BD_F_brd_V02_OCP.brd")
		(comment 1 "Grand Teton / footprints 7239-7246 of 9728")
	)
	(layers
		(0 "F.Cu" signal "TOP")
		(4 "In1.Cu" signal "GND")
		(6 "In2.Cu" signal "VCC")
		(8 "In3.Cu" signal "VCC1")
		(10 "In4.Cu" signal "GND1")
		(12 "In5.Cu" signal "IN1")
		(14 "In6.Cu" signal "GND2")
		(16 "In7.Cu" signal "IN2")
		(18 "In8.Cu" signal "GND3")
		(20 "In9.Cu" signal "IN3")
		(22 "In10.Cu" signal "GND4")
		(24 "In11.Cu" signal "IN4")
		(26 "In12.Cu" signal "GND5")
		(28 "In13.Cu" signal "IN5")
		(30 "In14.Cu" signal "GND6")
		(32 "In15.Cu" signal "IN6")
		(34 "In16.Cu" signal "GND7")
		(2 "B.Cu" signal "BOTTOM")
		(9 "F.Adhes" user "F.Adhesive")
		(11 "B.Adhes" user "B.Adhesive")
		(13 "F.Paste" user "Package Geometry/Pastemask Top")
		(15 "B.Paste" user "Package Geometry/Pastemask Bottom")
		(5 "F.SilkS" user "Ref Des/Silkscreen Top")
		(7 "B.SilkS" user "Ref Des/Silkscreen Bottom")
		(1 "F.Mask" user "Board Geometry/Soldermask Top")
		(3 "B.Mask" user "Board Geometry/Soldermask Bottom")
		(17 "Dwgs.User" user "User.Drawings")
		(19 "Cmts.User" user "User.Comments")
		(21 "Eco1.User" user "User.Eco1")
		(23 "Eco2.User" user "User.Eco2")
		(25 "Edge.Cuts" user "Board Geometry/Outline")
		(27 "Margin" user)
		(31 "F.CrtYd" user "Package Geometry/Place Bound Top")
		(29 "B.CrtYd" user "Package Geometry/Place Bound Bottom")
		(35 "F.Fab" user "Ref Des/Assembly Top")
		(33 "B.Fab" user "Ref Des/Assembly Bottom")
	)
	(footprint ""
		(layer "B.Cu")
		(at 404.30704 -136.652 -90)
		(property "Reference" "R342"
			(at 0 0 90)
			(layer "B.SilkS")
			(hide yes)
			(effects
				(font
					(size 1.27 1.27)
				)
				(justify mirror)
			)
		)
		(property "Value" ""
			(at 0 0 90)
			(layer "B.Fab")
			(effects
				(font
					(size 1.27 1.27)
				)
				(justify mirror)
			)
		)
		(duplicate_pad_numbers_are_jumpers no)
		(fp_line
			(start -0.7874 0.4064)
			(end 0.7874 0.4064)
			(stroke
				(width 0.1524)
				(type default)
			)
			(layer "B.SilkS")
		)
		(fp_line
			(start 0.7874 0.4064)
			(end 0.7874 -0.4064)
			(stroke
				(width 0.1524)
				(type default)
			)
			(layer "B.SilkS")
		)
		(fp_line
			(start -0.7874 -0.4064)
			(end -0.7874 0.4064)
			(stroke
				(width 0.1524)
				(type default)
			)
			(layer "B.SilkS")
		)
		(fp_line
			(start 0.7874 -0.4064)
			(end -0.7874 -0.4064)
			(stroke
				(width 0.1524)
				(type default)
			)
			(layer "B.SilkS")
		)
		(fp_line
			(start -0.67945 0.3048)
			(end -0.120396 0.3048)
			(stroke
				(width 0.1)
				(type default)
			)
			(layer "B.Fab")
		)
		(fp_line
			(start -0.120396 0.3048)
			(end -0.120396 0.2794)
			(stroke
				(width 0.1)
				(type default)
			)
			(layer "B.Fab")
		)
		(fp_line
			(start 0.12065 0.3048)
			(end 0.67945 0.3048)
			(stroke
				(width 0.1)
				(type default)
			)
			(layer "B.Fab")
		)
		(fp_line
			(start 0.67945 0.3048)
			(end 0.67945 -0.305054)
			(stroke
				(width 0.1)
				(type default)
			)
			(layer "B.Fab")
		)
		(fp_line
			(start -0.120396 0.2794)
			(end 0.12065 0.2794)
			(stroke
				(width 0.1)
				(type default)
			)
			(layer "B.Fab")
		)
		(fp_line
			(start 0.12065 0.2794)
			(end 0.12065 0.3048)
			(stroke
				(width 0.1)
				(type default)
			)
			(layer "B.Fab")
		)
		(fp_line
			(start -0.12065 -0.2794)
			(end -0.12065 -0.3048)
			(stroke
				(width 0.1)
				(type default)
			)
			(layer "B.Fab")
		)
		(fp_line
			(start 0.12065 -0.2794)
			(end -0.12065 -0.2794)
			(stroke
				(width 0.1)
				(type default)
			)
			(layer "B.Fab")
		)
		(fp_line
			(start -0.67945 -0.3048)
			(end -0.67945 0.3048)
			(stroke
				(width 0.1)
				(type default)
			)
			(layer "B.Fab")
		)
		(fp_line
			(start -0.12065 -0.3048)
			(end -0.67945 -0.3048)
			(stroke
				(width 0.1)
				(type default)
			)
			(layer "B.Fab")
		)
		(fp_line
			(start 0.12065 -0.305054)
			(end 0.12065 -0.2794)
			(stroke
				(width 0.1)
				(type default)
			)
			(layer "B.Fab")
		)
		(fp_line
			(start 0.67945 -0.305054)
			(end 0.12065 -0.305054)
			(stroke
				(width 0.1)
				(type default)
			)
			(layer "B.Fab")
		)
		(pad "1" smd circle
			(at 0.40005 0 90)
			(size 0 0)
			(layers "B.Cu" "B.Mask" "B.Paste")
			(net "RST_SMB_NIC_MUX_R_N")
		)
		(pad "2" smd circle
			(at -0.40005 0 90)
			(size 0 0)
			(layers "B.Cu" "B.Mask" "B.Paste")
			(net "RST_SMB_NIC6_MUX_N")
		)
	)
	(footprint ""
		(layer "B.Cu")
		(at 234.810046 -145.507202)
		(property "Reference" "R4186"
			(at 0 0 0)
			(layer "B.SilkS")
			(hide yes)
			(effects
				(font
					(size 1.27 1.27)
				)
				(justify mirror)
			)
		)
		(property "Value" ""
			(at 0 0 0)
			(layer "B.Fab")
			(effects
				(font
					(size 1.27 1.27)
				)
				(justify mirror)
			)
		)
		(duplicate_pad_numbers_are_jumpers no)
		(fp_line
			(start -1.2954 -0.5842)
			(end -1.2954 0.5842)
			(stroke
				(width 0.1524)
				(type default)
			)
			(layer "B.SilkS")
		)
		(fp_line
			(start -1.2954 0.5842)
			(end 1.2954 0.5842)
			(stroke
				(width 0.1524)
				(type default)
			)
			(layer "B.SilkS")
		)
		(fp_line
			(start 1.2954 -0.5842)
			(end -1.2954 -0.5842)
			(stroke
				(width 0.1524)
				(type default)
			)
			(layer "B.SilkS")
		)
		(fp_line
			(start 1.2954 0.5842)
			(end 1.2954 -0.5842)
			(stroke
				(width 0.1524)
				(type default)
			)
			(layer "B.SilkS")
		)
		(fp_line
			(start -1.1938 -0.406654)
			(end -1.1938 0.4064)
			(stroke
				(width 0.1)
				(type default)
			)
			(layer "B.Fab")
		)
		(fp_line
			(start -1.1938 0.4064)
			(end -0.8636 0.4064)
			(stroke
				(width 0.1)
				(type default)
			)
			(layer "B.Fab")
		)
		(fp_line
			(start -0.8636 -0.4572)
			(end -0.8636 -0.406654)
			(stroke
				(width 0.1)
				(type default)
			)
			(layer "B.Fab")
		)
		(fp_line
			(start -0.8636 -0.406654)
			(end -1.1938 -0.406654)
			(stroke
				(width 0.1)
				(type default)
			)
			(layer "B.Fab")
		)
		(fp_line
			(start -0.8636 0.4064)
			(end -0.8636 0.4572)
			(stroke
				(width 0.1)
				(type default)
			)
			(layer "B.Fab")
		)
		(fp_line
			(start -0.8636 0.4572)
			(end 0.8636 0.4572)
			(stroke
				(width 0.1)
				(type default)
			)
			(layer "B.Fab")
		)
		(fp_line
			(start 0.8636 -0.4572)
			(end -0.8636 -0.4572)
			(stroke
				(width 0.1)
				(type default)
			)
			(layer "B.Fab")
		)
		(fp_line
			(start 0.8636 -0.406654)
			(end 0.8636 -0.4572)
			(stroke
				(width 0.1)
				(type default)
			)
			(layer "B.Fab")
		)
		(fp_line
			(start 0.8636 0.4064)
			(end 1.1938 0.4064)
			(stroke
				(width 0.1)
				(type default)
			)
			(layer "B.Fab")
		)
		(fp_line
			(start 0.8636 0.4318)
			(end 0.8636 0.4064)
			(stroke
				(width 0.1)
				(type default)
			)
			(layer "B.Fab")
		)
		(fp_line
			(start 0.8636 0.4572)
			(end 0.8636 0.4318)
			(stroke
				(width 0.1)
				(type default)
			)
			(layer "B.Fab")
		)
		(fp_line
			(start 1.1938 -0.406654)
			(end 0.8636 -0.406654)
			(stroke
				(width 0.1)
				(type default)
			)
			(layer "B.Fab")
		)
		(fp_line
			(start 1.1938 0.4064)
			(end 1.1938 -0.406654)
			(stroke
				(width 0.1)
				(type default)
			)
			(layer "B.Fab")
		)
		(pad "1" smd rect
			(at 0.7366 0 270)
			(size 0.7112 0.8128)
			(layers "B.Cu" "B.Mask" "B.Paste")
			(net "P3V3_CLK_GEN_VDD_CK440_PEX")
		)
		(pad "2" smd rect
			(at -0.7366 0 270)
			(size 0.7112 0.8128)
			(layers "B.Cu" "B.Mask" "B.Paste")
			(net "P3V3_CLK_GEN_VDDA100M_CK440_PEX")
		)
	)
	(footprint ""
		(layer "B.Cu")
		(at 126.646178 -200.72985 180)
		(property "Reference" "R924"
			(at 0 0 0)
			(layer "B.SilkS")
			(hide yes)
			(effects
				(font
					(size 1.27 1.27)
				)
				(justify mirror)
			)
		)
		(property "Value" ""
			(at 0 0 0)
			(layer "B.Fab")
			(effects
				(font
					(size 1.27 1.27)
				)
				(justify mirror)
			)
		)
		(duplicate_pad_numbers_are_jumpers no)
		(fp_line
			(start 0.7874 0.4064)
			(end 0.7874 -0.4064)
			(stroke
				(width 0.1524)
				(type default)
			)
			(layer "B.SilkS")
		)
		(fp_line
			(start 0.7874 -0.4064)
			(end -0.7874 -0.4064)
			(stroke
				(width 0.1524)
				(type default)
			)
			(layer "B.SilkS")
		)
		(fp_line
			(start -0.7874 0.4064)
			(end 0.7874 0.4064)
			(stroke
				(width 0.1524)
				(type default)
			)
			(layer "B.SilkS")
		)
		(fp_line
			(start -0.7874 -0.4064)
			(end -0.7874 0.4064)
			(stroke
				(width 0.1524)
				(type default)
			)
			(layer "B.SilkS")
		)
		(fp_line
			(start 0.67945 0.3048)
			(end 0.67945 -0.305054)
			(stroke
				(width 0.1)
				(type default)
			)
			(layer "B.Fab")
		)
		(fp_line
			(start 0.67945 -0.305054)
			(end 0.12065 -0.305054)
			(stroke
				(width 0.1)
				(type default)
			)
			(layer "B.Fab")
		)
		(fp_line
			(start 0.12065 0.3048)
			(end 0.67945 0.3048)
			(stroke
				(width 0.1)
				(type default)
			)
			(layer "B.Fab")
		)
		(fp_line
			(start 0.12065 0.2794)
			(end 0.12065 0.3048)
			(stroke
				(width 0.1)
				(type default)
			)
			(layer "B.Fab")
		)
		(fp_line
			(start 0.12065 -0.2794)
			(end -0.12065 -0.2794)
			(stroke
				(width 0.1)
				(type default)
			)
			(layer "B.Fab")
		)
		(fp_line
			(start 0.12065 -0.305054)
			(end 0.12065 -0.2794)
			(stroke
				(width 0.1)
				(type default)
			)
			(layer "B.Fab")
		)
		(fp_line
			(start -0.120396 0.3048)
			(end -0.120396 0.2794)
			(stroke
				(width 0.1)
				(type default)
			)
			(layer "B.Fab")
		)
		(fp_line
			(start -0.120396 0.2794)
			(end 0.12065 0.2794)
			(stroke
				(width 0.1)
				(type default)
			)
			(layer "B.Fab")
		)
		(fp_line
			(start -0.12065 -0.2794)
			(end -0.12065 -0.3048)
			(stroke
				(width 0.1)
				(type default)
			)
			(layer "B.Fab")
		)
		(fp_line
			(start -0.12065 -0.3048)
			(end -0.67945 -0.3048)
			(stroke
				(width 0.1)
				(type default)
			)
			(layer "B.Fab")
		)
		(fp_line
			(start -0.67945 0.3048)
			(end -0.120396 0.3048)
			(stroke
				(width 0.1)
				(type default)
			)
			(layer "B.Fab")
		)
		(fp_line
			(start -0.67945 -0.3048)
			(end -0.67945 0.3048)
			(stroke
				(width 0.1)
				(type default)
			)
			(layer "B.Fab")
		)
		(pad "1" smd circle
			(at 0.40005 0)
			(size 0 0)
			(layers "B.Cu" "B.Mask" "B.Paste")
			(net "FT4232_CLI_EEPROM_R_SDA")
		)
		(pad "2" smd circle
			(at -0.40005 0)
			(size 0 0)
			(layers "B.Cu" "B.Mask" "B.Paste")
			(net "FT4232_CLI_EEPROM_SDA")
		)
	)
	(footprint ""
		(layer "B.Cu")
		(at 338.093812 -212.386926 90)
		(property "Reference" "C2052"
			(at 0 0 90)
			(layer "B.SilkS")
			(hide yes)
			(effects
				(font
					(size 1.27 1.27)
				)
				(justify mirror)
			)
		)
		(property "Value" ""
			(at 0 0 90)
			(layer "B.Fab")
			(effects
				(font
					(size 1.27 1.27)
				)
				(justify mirror)
			)
		)
		(duplicate_pad_numbers_are_jumpers no)
		(fp_line
			(start 0.69215 -0.2921)
			(end -0.69215 -0.2921)
			(stroke
				(width 0.1524)
				(type default)
			)
			(layer "B.SilkS")
		)
		(fp_line
			(start -0.69215 -0.2921)
			(end -0.69215 0.2921)
			(stroke
				(width 0.1524)
				(type default)
			)
			(layer "B.SilkS")
		)
		(fp_line
			(start 0.69215 0.2921)
			(end 0.69215 -0.2921)
			(stroke
				(width 0.1524)
				(type default)
			)
			(layer "B.SilkS")
		)
		(fp_line
			(start -0.69215 0.2921)
			(end 0.69215 0.2921)
			(stroke
				(width 0.1524)
				(type default)
			)
			(layer "B.SilkS")
		)
		(fp_line
			(start 0.51435 -0.2794)
			(end -0.51435 -0.2794)
			(stroke
				(width 0.1)
				(type default)
			)
			(layer "B.Fab")
		)
		(fp_line
			(start -0.51435 -0.2794)
			(end -0.51435 0.2794)
			(stroke
				(width 0.1)
				(type default)
			)
			(layer "B.Fab")
		)
		(fp_line
			(start 0.51435 0.2794)
			(end 0.51435 -0.2794)
			(stroke
				(width 0.1)
				(type default)
			)
			(layer "B.Fab")
		)
		(fp_line
			(start -0.51435 0.2794)
			(end 0.51435 0.2794)
			(stroke
				(width 0.1)
				(type default)
			)
			(layer "B.Fab")
		)
		(pad "1" smd circle
			(at 0.40005 0 270)
			(size 0 0)
			(layers "B.Cu" "B.Mask" "B.Paste")
			(net "P3V3_FPGA_VCCIO2")
		)
		(pad "2" smd circle
			(at -0.40005 0 270)
			(size 0 0)
			(layers "B.Cu" "B.Mask" "B.Paste")
			(net "GND")
		)
		(zone
			(layer "B.Cu")
			(hatch none 0.5)
			(connect_pads
				(clearance 0)
			)
			(min_thickness 0.25)
			(keepout
				(tracks not_allowed)
				(vias allowed)
				(pads allowed)
				(copperpour not_allowed)
				(footprints allowed)
			)
			(placement
				(enabled no)
				(sheetname "")
			)
			(fill
				(thermal_gap 0.5)
				(thermal_bridge_width 0.5)
				(island_removal_mode 0)
			)
			(polygon
				(pts
					(xy 338.181442 -212.577426) (xy 338.239608 -212.485986) (xy 338.239608 -212.286596) (xy 338.181442 -212.196426)
					(xy 338.006182 -212.196426) (xy 337.947762 -212.286596) (xy 337.947762 -212.485986) (xy 338.005928 -212.577426)
				)
			)
		)
	)
	(footprint ""
		(layer "B.Cu")
		(at 134.292594 -328.422)
		(property "Reference" "PJ20"
			(at 0 0 0)
			(layer "B.SilkS")
			(hide yes)
			(effects
				(font
					(size 1.27 1.27)
				)
				(justify mirror)
			)
		)
		(property "Value" ""
			(at 0 0 0)
			(layer "B.Fab")
			(effects
				(font
					(size 1.27 1.27)
				)
				(justify mirror)
			)
		)
		(duplicate_pad_numbers_are_jumpers no)
		(pad "1" smd circle
			(at 0.40005 0 90)
			(size 0 0)
			(layers "B.Cu" "B.Mask" "B.Paste")
			(net "VSENSE_P0V8_PEX1_SKT_VSEN")
		)
		(pad "2" smd rect
			(at -0.40005 0)
			(size 0.4572 0.508)
			(layers "B.Cu" "B.Mask" "B.Paste")
			(net "SH_P0V8_PEX1_VSEN1_L")
		)
		(zone
			(layer "B.Cu")
			(hatch none 0.5)
			(connect_pads
				(clearance 0)
			)
			(min_thickness 0.25)
			(keepout
				(tracks allowed)
				(vias not_allowed)
				(pads allowed)
				(copperpour not_allowed)
				(footprints allowed)
			)
			(placement
				(enabled no)
				(sheetname "")
			)
			(fill
				(thermal_gap 0.5)
				(thermal_bridge_width 0.5)
				(island_removal_mode 0)
			)
			(polygon
				(pts
					(xy 133.606794 -328.1172) (xy 133.606794 -328.7268) (xy 134.978394 -328.7268) (xy 134.978394 -328.1172)
				)
			)
		)
	)
	(footprint ""
		(layer "B.Cu")
		(at 281.399742 -291.624766)
		(property "Reference" "C1616"
			(at 0 0 0)
			(layer "B.SilkS")
			(hide yes)
			(effects
				(font
					(size 1.27 1.27)
				)
				(justify mirror)
			)
		)
		(property "Value" ""
			(at 0 0 0)
			(layer "B.Fab")
			(effects
				(font
					(size 1.27 1.27)
				)
				(justify mirror)
			)
		)
		(duplicate_pad_numbers_are_jumpers no)
		(fp_line
			(start -0.299974 -0.150114)
			(end -0.299974 0.150114)
			(stroke
				(width 0.1)
				(type default)
			)
			(layer "B.Fab")
		)
		(fp_line
			(start -0.299974 0.150114)
			(end 0.299974 0.150114)
			(stroke
				(width 0.1)
				(type default)
			)
			(layer "B.Fab")
		)
		(fp_line
			(start 0.299974 -0.150114)
			(end -0.299974 -0.150114)
			(stroke
				(width 0.1)
				(type default)
			)
			(layer "B.Fab")
		)
		(fp_line
			(start 0.299974 0.150114)
			(end 0.299974 -0.150114)
			(stroke
				(width 0.1)
				(type default)
			)
			(layer "B.Fab")
		)
		(pad "1" smd rect
			(at 0.2667 0 180)
			(size 0.3048 0.381)
			(layers "B.Cu" "B.Mask" "B.Paste")
			(net "P0V8_PEX2")
		)
		(pad "2" smd rect
			(at -0.2667 0 180)
			(size 0.3048 0.381)
			(layers "B.Cu" "B.Mask" "B.Paste")
			(net "GND")
		)
	)
	(footprint ""
		(layer "B.Cu")
		(at 102.156006 -357.923084 90)
		(property "Reference" "R6376"
			(at 0 0 90)
			(layer "B.SilkS")
			(hide yes)
			(effects
				(font
					(size 1.27 1.27)
				)
				(justify mirror)
			)
		)
		(property "Value" ""
			(at 0 0 90)
			(layer "B.Fab")
			(effects
				(font
					(size 1.27 1.27)
				)
				(justify mirror)
			)
		)
		(duplicate_pad_numbers_are_jumpers no)
		(fp_line
			(start 0.7874 -0.4064)
			(end -0.7874 -0.4064)
			(stroke
				(width 0.1524)
				(type default)
			)
			(layer "B.SilkS")
		)
		(fp_line
			(start -0.7874 -0.4064)
			(end -0.7874 0.4064)
			(stroke
				(width 0.1524)
				(type default)
			)
			(layer "B.SilkS")
		)
		(fp_line
			(start 0.7874 0.4064)
			(end 0.7874 -0.4064)
			(stroke
				(width 0.1524)
				(type default)
			)
			(layer "B.SilkS")
		)
		(fp_line
			(start -0.7874 0.4064)
			(end 0.7874 0.4064)
			(stroke
				(width 0.1524)
				(type default)
			)
			(layer "B.SilkS")
		)
		(fp_line
			(start 0.67945 -0.305054)
			(end 0.12065 -0.305054)
			(stroke
				(width 0.1)
				(type default)
			)
			(layer "B.Fab")
		)
		(fp_line
			(start 0.12065 -0.305054)
			(end 0.12065 -0.2794)
			(stroke
				(width 0.1)
				(type default)
			)
			(layer "B.Fab")
		)
		(fp_line
			(start -0.12065 -0.3048)
			(end -0.67945 -0.3048)
			(stroke
				(width 0.1)
				(type default)
			)
			(layer "B.Fab")
		)
		(fp_line
			(start -0.67945 -0.3048)
			(end -0.67945 0.3048)
			(stroke
				(width 0.1)
				(type default)
			)
			(layer "B.Fab")
		)
		(fp_line
			(start 0.12065 -0.2794)
			(end -0.12065 -0.2794)
			(stroke
				(width 0.1)
				(type default)
			)
			(layer "B.Fab")
		)
		(fp_line
			(start -0.12065 -0.2794)
			(end -0.12065 -0.3048)
			(stroke
				(width 0.1)
				(type default)
			)
			(layer "B.Fab")
		)
		(fp_line
			(start 0.12065 0.2794)
			(end 0.12065 0.3048)
			(stroke
				(width 0.1)
				(type default)
			)
			(layer "B.Fab")
		)
		(fp_line
			(start -0.120396 0.2794)
			(end 0.12065 0.2794)
			(stroke
				(width 0.1)
				(type default)
			)
			(layer "B.Fab")
		)
		(fp_line
			(start 0.67945 0.3048)
			(end 0.67945 -0.305054)
			(stroke
				(width 0.1)
				(type default)
			)
			(layer "B.Fab")
		)
		(fp_line
			(start 0.12065 0.3048)
			(end 0.67945 0.3048)
			(stroke
				(width 0.1)
				(type default)
			)
			(layer "B.Fab")
		)
		(fp_line
			(start -0.120396 0.3048)
			(end -0.120396 0.2794)
			(stroke
				(width 0.1)
				(type default)
			)
			(layer "B.Fab")
		)
		(fp_line
			(start -0.67945 0.3048)
			(end -0.120396 0.3048)
			(stroke
				(width 0.1)
				(type default)
			)
			(layer "B.Fab")
		)
		(pad "1" smd circle
			(at 0.40005 0 270)
			(size 0 0)
			(layers "B.Cu" "B.Mask" "B.Paste")
			(net "CLK_100M_DB800ZL_PEX1_S3_R_DP")
		)
		(pad "2" smd circle
			(at -0.40005 0 270)
			(size 0 0)
			(layers "B.Cu" "B.Mask" "B.Paste")
			(net "CLK_100M_DB800ZL_PEX1_S3_DP")
		)
	)
	(footprint ""
		(layer "B.Cu")
		(at 406.999948 -303.499774 -90)
		(property "Reference" "C3462"
			(at 0 0 90)
			(layer "B.SilkS")
			(hide yes)
			(effects
				(font
					(size 1.27 1.27)
				)
				(justify mirror)
			)
		)
		(property "Value" ""
			(at 0 0 90)
			(layer "B.Fab")
			(effects
				(font
					(size 1.27 1.27)
				)
				(justify mirror)
			)
		)
		(duplicate_pad_numbers_are_jumpers no)
		(fp_line
			(start -0.299974 0.150114)
			(end 0.299974 0.150114)
			(stroke
				(width 0.1)
				(type default)
			)
			(layer "B.Fab")
		)
		(fp_line
			(start 0.299974 0.150114)
			(end 0.299974 -0.150114)
			(stroke
				(width 0.1)
				(type default)
			)
			(layer "B.Fab")
		)
		(fp_line
			(start -0.299974 -0.150114)
			(end -0.299974 0.150114)
			(stroke
				(width 0.1)
				(type default)
			)
			(layer "B.Fab")
		)
		(fp_line
			(start 0.299974 -0.150114)
			(end -0.299974 -0.150114)
			(stroke
				(width 0.1)
				(type default)
			)
			(layer "B.Fab")
		)
		(pad "1" smd rect
			(at 0.2667 0 90)
			(size 0.3048 0.381)
			(layers "B.Cu" "B.Mask" "B.Paste")
			(net "P1V25_PEX3")
		)
		(pad "2" smd rect
			(at -0.2667 0 90)
			(size 0.3048 0.381)
			(layers "B.Cu" "B.Mask" "B.Paste")
			(net "GND")
		)
	)
)
